# BASEBOARD_FAB2 (Tioga Pass) — schematic netlist excerpt (pin names and nets, part order shuffled) for the footprints in the layout excerpt that follows; sources: Cadence DE-HDL packaged netlist, KiCad conversion of Wiwynn_Tioga_Pass_MB.brd

C7A34  CAP  3300PF 50V 10% EMPTY  pkg 0402LF  page 232 : A = VR_PVPP_DEF_PHASE ; B = VR_PVPP_DEF_SNUB
C1D35  CAP  1.0UF 16V 10% X6S  pkg 0402  page 207 : A = VR_FET_SW_P12V_STBY_PVCCIN_CPU1 ; B = GND
C2G8  CAP_A  47UF 4V 20% X5R  pkg 0603V  page 225 : A = PVDDQ_GHJ ; B = GND

(kicad_pcb
	(version 20260206)
	(generator "pcbnew")
	(generator_version "10.0")
	(general
		(thickness 1.6)
		(legacy_teardrops no)
	)
	(paper "A4")
	(title_block
		(title "Wiwynn_Tioga_Pass_MB.brd")
		(comment 1 "Tioga Pass / footprints 526-528 of 4770")
	)
	(layers
		(0 "F.Cu" signal "TOP")
		(4 "In1.Cu" signal "L2GND")
		(6 "In2.Cu" signal "L3")
		(8 "In3.Cu" signal "L4GND")
		(10 "In4.Cu" signal "L5")
		(12 "In5.Cu" signal "L6GND")
		(14 "In6.Cu" signal "L7VCC")
		(16 "In7.Cu" signal "L8VCC")
		(18 "In8.Cu" signal "L9GND")
		(20 "In9.Cu" signal "L10")
		(22 "In10.Cu" signal "L11GND")
		(24 "In11.Cu" signal "L12")
		(26 "In12.Cu" signal "L13GND")
		(2 "B.Cu" signal "BOTTOM")
		(9 "F.Adhes" user "F.Adhesive")
		(11 "B.Adhes" user "B.Adhesive")
		(13 "F.Paste" user "Package Geometry/Pastemask Top")
		(15 "B.Paste" user "Package Geometry/Pastemask Bottom")
		(5 "F.SilkS" user "Ref Des/Silkscreen Top")
		(7 "B.SilkS" user "Ref Des/Silkscreen Bottom")
		(1 "F.Mask" user "Board Geometry/Soldermask Top")
		(3 "B.Mask" user "Board Geometry/Soldermask Bottom")
		(17 "Dwgs.User" user "User.Drawings")
		(19 "Cmts.User" user "User.Comments")
		(21 "Eco1.User" user "User.Eco1")
		(23 "Eco2.User" user "User.Eco2")
		(25 "Edge.Cuts" user "Board Geometry/Outline")
		(27 "Margin" user)
		(31 "F.CrtYd" user "Package Geometry/Place Bound Top")
		(29 "B.CrtYd" user "Package Geometry/Place Bound Bottom")
		(35 "F.Fab" user "Ref Des/Assembly Top")
		(33 "B.Fab" user "Ref Des/Assembly Bottom")
	)
	(footprint ""
		(layer "F.Cu")
		(at 340.614 -137.1727 90)
		(property "Reference" "C7A34"
			(at 0 0 90)
			(layer "F.SilkS")
			(hide yes)
			(effects
				(font
					(size 1.27 1.27)
				)
			)
		)
		(property "Value" ""
			(at 0 0 90)
			(layer "F.Fab")
			(effects
				(font
					(size 1.27 1.27)
				)
			)
		)
		(duplicate_pad_numbers_are_jumpers no)
		(fp_poly
			(pts
				(xy 0.3048 -0.1016) (xy 0.3048 0.9906) (xy -0.3048 0.9906) (xy -0.3048 -0.1016)
			)
			(stroke
				(width 0)
				(type default)
			)
			(fill no)
			(layer "F.CrtYd")
		)
		(fp_line
			(start 0.3048 -0.1016)
			(end -0.3048 -0.1016)
			(stroke
				(width 0.1)
				(type default)
			)
			(layer "F.Fab")
		)
		(fp_line
			(start -0.3048 -0.1016)
			(end -0.3048 0.9906)
			(stroke
				(width 0.1)
				(type default)
			)
			(layer "F.Fab")
		)
		(fp_line
			(start 0.3048 0.9906)
			(end 0.3048 -0.1016)
			(stroke
				(width 0.1)
				(type default)
			)
			(layer "F.Fab")
		)
		(fp_line
			(start -0.3048 0.9906)
			(end 0.3048 0.9906)
			(stroke
				(width 0.1)
				(type default)
			)
			(layer "F.Fab")
		)
		(pad "1" smd rect
			(at 0 0 90)
			(size 0.508 0.508)
			(layers "F.Cu" "F.Mask" "F.Paste")
			(net "VR_PVPP_DEF_PHASE")
		)
		(pad "2" smd rect
			(at 0 0.889 90)
			(size 0.508 0.508)
			(layers "F.Cu" "F.Mask" "F.Paste")
			(net "VR_PVPP_DEF_SNUB")
		)
		(zone
			(layer "F.Cu")
			(hatch none 0.5)
			(connect_pads
				(clearance 0)
			)
			(min_thickness 0.25)
			(keepout
				(tracks allowed)
				(vias not_allowed)
				(pads allowed)
				(copperpour not_allowed)
				(footprints allowed)
			)
			(placement
				(enabled no)
				(sheetname "")
			)
			(fill
				(thermal_gap 0.5)
				(thermal_bridge_width 0.5)
				(island_removal_mode 0)
			)
			(polygon
				(pts
					(xy 340.868 -136.9187) (xy 340.868 -137.4267) (xy 341.249 -137.4267) (xy 341.249 -136.9187)
				)
			)
		)
		(zone
			(layer "F.Cu")
			(hatch none 0.5)
			(connect_pads
				(clearance 0)
			)
			(min_thickness 0.25)
			(keepout
				(tracks not_allowed)
				(vias allowed)
				(pads allowed)
				(copperpour not_allowed)
				(footprints allowed)
			)
			(placement
				(enabled no)
				(sheetname "")
			)
			(fill
				(thermal_gap 0.5)
				(thermal_bridge_width 0.5)
				(island_removal_mode 0)
			)
			(polygon
				(pts
					(xy 341.249 -136.9187) (xy 341.249 -137.4267) (xy 340.868 -137.4267) (xy 340.868 -136.9187)
				)
			)
		)
	)
	(footprint ""
		(layer "F.Cu")
		(at 29.6164 -67.757802 -90)
		(property "Reference" "C1D35"
			(at 0 0 270)
			(layer "F.SilkS")
			(hide yes)
			(effects
				(font
					(size 1.27 1.27)
				)
			)
		)
		(property "Value" ""
			(at 0 0 270)
			(layer "F.Fab")
			(effects
				(font
					(size 1.27 1.27)
				)
			)
		)
		(duplicate_pad_numbers_are_jumpers no)
		(fp_rect
			(start 0.3048 -0.1016)
			(end -0.3048 0.9906)
			(stroke
				(width 0)
				(type default)
			)
			(fill no)
			(layer "F.CrtYd")
		)
		(fp_line
			(start -0.3048 0.9906)
			(end 0.3048 0.9906)
			(stroke
				(width 0.1)
				(type default)
			)
			(layer "F.Fab")
		)
		(fp_line
			(start 0.3048 0.9906)
			(end 0.3048 -0.1016)
			(stroke
				(width 0.1)
				(type default)
			)
			(layer "F.Fab")
		)
		(fp_line
			(start -0.3048 -0.1016)
			(end -0.3048 0.9906)
			(stroke
				(width 0.1)
				(type default)
			)
			(layer "F.Fab")
		)
		(fp_line
			(start 0.3048 -0.1016)
			(end -0.3048 -0.1016)
			(stroke
				(width 0.1)
				(type default)
			)
			(layer "F.Fab")
		)
		(pad "1" smd rect
			(at 0 0 270)
			(size 0.508 0.508)
			(layers "F.Cu" "F.Mask" "F.Paste")
			(net "VR_FET_SW_P12V_STBY_PVCCIN_CPU1")
		)
		(pad "2" smd rect
			(at 0 0.889 270)
			(size 0.508 0.508)
			(layers "F.Cu" "F.Mask" "F.Paste")
			(net "GND")
		)
		(zone
			(layer "F.Cu")
			(hatch none 0.5)
			(connect_pads
				(clearance 0)
			)
			(min_thickness 0.25)
			(keepout
				(tracks allowed)
				(vias not_allowed)
				(pads allowed)
				(copperpour not_allowed)
				(footprints allowed)
			)
			(placement
				(enabled no)
				(sheetname "")
			)
			(fill
				(thermal_gap 0.5)
				(thermal_bridge_width 0.5)
				(island_removal_mode 0)
			)
			(polygon
				(pts
					(xy 29.3624 -67.503802) (xy 29.3624 -68.011802) (xy 28.9814 -68.011802) (xy 28.9814 -67.503802)
				)
			)
		)
		(zone
			(layer "F.Cu")
			(hatch none 0.5)
			(connect_pads
				(clearance 0)
			)
			(min_thickness 0.25)
			(keepout
				(tracks not_allowed)
				(vias allowed)
				(pads allowed)
				(copperpour not_allowed)
				(footprints allowed)
			)
			(placement
				(enabled no)
				(sheetname "")
			)
			(fill
				(thermal_gap 0.5)
				(thermal_bridge_width 0.5)
				(island_removal_mode 0)
			)
			(polygon
				(pts
					(xy 29.3624 -67.503802) (xy 29.3624 -68.011802) (xy 28.9814 -68.011802) (xy 28.9814 -67.503802)
				)
			)
		)
	)
	(footprint ""
		(layer "F.Cu")
		(at 93.136212 -12.824968 -90)
		(property "Reference" "C2G8"
			(at 0 0 270)
			(layer "F.SilkS")
			(hide yes)
			(effects
				(font
					(size 1.27 1.27)
				)
			)
		)
		(property "Value" ""
			(at 0 0 270)
			(layer "F.Fab")
			(effects
				(font
					(size 1.27 1.27)
				)
			)
		)
		(duplicate_pad_numbers_are_jumpers no)
		(fp_rect
			(start -0.500126 1.598422)
			(end 0.500126 -0.201422)
			(stroke
				(width 0)
				(type default)
			)
			(fill no)
			(layer "F.CrtYd")
		)
		(fp_line
			(start -0.500126 1.598422)
			(end -0.500126 -0.201422)
			(stroke
				(width 0.1)
				(type default)
			)
			(layer "F.Fab")
		)
		(fp_line
			(start 0.500126 1.598422)
			(end -0.500126 1.598422)
			(stroke
				(width 0.1)
				(type default)
			)
			(layer "F.Fab")
		)
		(fp_line
			(start -0.500126 -0.201422)
			(end 0.500126 -0.201422)
			(stroke
				(width 0.1)
				(type default)
			)
			(layer "F.Fab")
		)
		(fp_line
			(start 0.500126 -0.201422)
			(end 0.500126 1.598422)
			(stroke
				(width 0.1)
				(type default)
			)
			(layer "F.Fab")
		)
		(pad "1" smd rect
			(at 0 0 180)
			(size 0.889 0.9906)
			(layers "F.Cu" "F.Mask" "F.Paste")
			(net "PVDDQ_GHJ")
		)
		(pad "2" smd rect
			(at 0 1.397 180)
			(size 0.889 0.9906)
			(layers "F.Cu" "F.Mask" "F.Paste")
			(net "GND")
		)
		(zone
			(layer "F.Cu")
			(hatch none 0.5)
			(connect_pads
				(clearance 0)
			)
			(min_thickness 0.25)
			(keepout
				(tracks allowed)
				(vias not_allowed)
				(pads allowed)
				(copperpour not_allowed)
				(footprints allowed)
			)
			(placement
				(enabled no)
				(sheetname "")
			)
			(fill
				(thermal_gap 0.5)
				(thermal_bridge_width 0.5)
				(island_removal_mode 0)
			)
			(polygon
				(pts
					(xy 92.183712 -13.320268) (xy 92.183712 -12.329668) (xy 92.691712 -12.329668) (xy 92.691712 -13.320268)
				)
			)
		)
		(zone
			(layer "F.Cu")
			(hatch none 0.5)
			(connect_pads
				(clearance 0)
			)
			(min_thickness 0.25)
			(keepout
				(tracks not_allowed)
				(vias allowed)
				(pads allowed)
				(copperpour not_allowed)
				(footprints allowed)
			)
			(placement
				(enabled no)
				(sheetname "")
			)
			(fill
				(thermal_gap 0.5)
				(thermal_bridge_width 0.5)
				(island_removal_mode 0)
			)
			(polygon
				(pts
					(xy 92.183712 -13.320268) (xy 92.183712 -12.329668) (xy 92.691712 -12.329668) (xy 92.691712 -13.320268)
				)
			)
		)
	)
)
